# T6G (Grand Teton) — schematic netlist excerpt (pin names and nets, part order shuffled) for the footprints in the layout excerpt that follows; sources: Cadence DE-HDL packaged netlist, KiCad conversion of 04192023_DAF0TMB3IC0_F0TG_MB_C_brd_V02_OCP.brd

PC2098  Q_CAP  1UF 25V 10% X6S  pkg C0402  page 140 : A = P12V_OCP_VCC_2 ; B = GND
R3269  Q_RES  1K 1% EMPTY  pkg 0402LF  page 111 : A = P3V3_AUX ; B = FM_P2E_FGB

(kicad_pcb
	(version 20260206)
	(generator "pcbnew")
	(generator_version "10.0")
	(general
		(thickness 1.6)
		(legacy_teardrops no)
	)
	(paper "A4")
	(title_block
		(title "04192023_DAF0TMB3IC0_F0TG_MB_C_brd_V02_OCP.brd")
		(comment 1 "Grand Teton / footprints 3662-3663 of 8354")
	)
	(layers
		(0 "F.Cu" signal "TOP")
		(4 "In1.Cu" signal "GND")
		(6 "In2.Cu" signal "IN1")
		(8 "In3.Cu" signal "GND1")
		(10 "In4.Cu" signal "IN2")
		(12 "In5.Cu" signal "GND2")
		(14 "In6.Cu" signal "IN3")
		(16 "In7.Cu" signal "GND3")
		(18 "In8.Cu" signal "VCC")
		(20 "In9.Cu" signal "VCC1")
		(22 "In10.Cu" signal "GND4")
		(24 "In11.Cu" signal "IN4")
		(26 "In12.Cu" signal "GND5")
		(28 "In13.Cu" signal "IN5")
		(30 "In14.Cu" signal "GND6")
		(32 "In15.Cu" signal "IN6")
		(34 "In16.Cu" signal "GND7")
		(2 "B.Cu" signal "BOTTOM")
		(9 "F.Adhes" user "F.Adhesive")
		(11 "B.Adhes" user "B.Adhesive")
		(13 "F.Paste" user "Package Geometry/Pastemask Top")
		(15 "B.Paste" user "Package Geometry/Pastemask Bottom")
		(5 "F.SilkS" user "Ref Des/Silkscreen Top")
		(7 "B.SilkS" user "Ref Des/Silkscreen Bottom")
		(1 "F.Mask" user "Board Geometry/Soldermask Top")
		(3 "B.Mask" user "Board Geometry/Soldermask Bottom")
		(17 "Dwgs.User" user "User.Drawings")
		(19 "Cmts.User" user "User.Comments")
		(21 "Eco1.User" user "User.Eco1")
		(23 "Eco2.User" user "User.Eco2")
		(25 "Edge.Cuts" user "Board Geometry/Outline")
		(27 "Margin" user)
		(31 "F.CrtYd" user "Package Geometry/Place Bound Top")
		(29 "B.CrtYd" user "Package Geometry/Place Bound Bottom")
		(35 "F.Fab" user "Ref Des/Assembly Top")
		(33 "B.Fab" user "Ref Des/Assembly Bottom")
	)
	(footprint ""
		(layer "F.Cu")
		(at 32.347662 -429.790098 -90)
		(property "Reference" "R3269"
			(at 0 0 270)
			(layer "F.SilkS")
			(hide yes)
			(effects
				(font
					(size 1.27 1.27)
				)
			)
		)
		(property "Value" ""
			(at 0 0 270)
			(layer "F.Fab")
			(effects
				(font
					(size 1.27 1.27)
				)
			)
		)
		(duplicate_pad_numbers_are_jumpers no)
		(fp_line
			(start -0.7874 0.4064)
			(end -0.7874 -0.4064)
			(stroke
				(width 0.1524)
				(type default)
			)
			(layer "F.SilkS")
		)
		(fp_line
			(start 0.7874 0.4064)
			(end -0.7874 0.4064)
			(stroke
				(width 0.1524)
				(type default)
			)
			(layer "F.SilkS")
		)
		(fp_line
			(start -0.7874 -0.4064)
			(end 0.7874 -0.4064)
			(stroke
				(width 0.1524)
				(type default)
			)
			(layer "F.SilkS")
		)
		(fp_line
			(start 0.7874 -0.4064)
			(end 0.7874 0.4064)
			(stroke
				(width 0.1524)
				(type default)
			)
			(layer "F.SilkS")
		)
		(fp_line
			(start -0.67945 0.3048)
			(end -0.67945 -0.305054)
			(stroke
				(width 0.1)
				(type default)
			)
			(layer "F.Fab")
		)
		(fp_line
			(start -0.12065 0.3048)
			(end -0.67945 0.3048)
			(stroke
				(width 0.1)
				(type default)
			)
			(layer "F.Fab")
		)
		(fp_line
			(start 0.120396 0.3048)
			(end 0.120396 0.2794)
			(stroke
				(width 0.1)
				(type default)
			)
			(layer "F.Fab")
		)
		(fp_line
			(start 0.67945 0.3048)
			(end 0.120396 0.3048)
			(stroke
				(width 0.1)
				(type default)
			)
			(layer "F.Fab")
		)
		(fp_line
			(start -0.12065 0.2794)
			(end -0.12065 0.3048)
			(stroke
				(width 0.1)
				(type default)
			)
			(layer "F.Fab")
		)
		(fp_line
			(start 0.120396 0.2794)
			(end -0.12065 0.2794)
			(stroke
				(width 0.1)
				(type default)
			)
			(layer "F.Fab")
		)
		(fp_line
			(start -0.12065 -0.2794)
			(end 0.12065 -0.2794)
			(stroke
				(width 0.1)
				(type default)
			)
			(layer "F.Fab")
		)
		(fp_line
			(start 0.12065 -0.2794)
			(end 0.12065 -0.3048)
			(stroke
				(width 0.1)
				(type default)
			)
			(layer "F.Fab")
		)
		(fp_line
			(start 0.12065 -0.3048)
			(end 0.67945 -0.3048)
			(stroke
				(width 0.1)
				(type default)
			)
			(layer "F.Fab")
		)
		(fp_line
			(start 0.67945 -0.3048)
			(end 0.67945 0.3048)
			(stroke
				(width 0.1)
				(type default)
			)
			(layer "F.Fab")
		)
		(fp_line
			(start -0.67945 -0.305054)
			(end -0.12065 -0.305054)
			(stroke
				(width 0.1)
				(type default)
			)
			(layer "F.Fab")
		)
		(fp_line
			(start -0.12065 -0.305054)
			(end -0.12065 -0.2794)
			(stroke
				(width 0.1)
				(type default)
			)
			(layer "F.Fab")
		)
		(pad "1" smd circle
			(at -0.40005 0 270)
			(size 0 0)
			(layers "F.Cu" "F.Mask" "F.Paste")
			(net "P3V3_AUX")
		)
		(pad "2" smd circle
			(at 0.40005 0 270)
			(size 0 0)
			(layers "F.Cu" "F.Mask" "F.Paste")
			(net "FM_P2E_FGB")
		)
	)
	(footprint ""
		(layer "F.Cu")
		(at 77.128878 -23.308818 180)
		(property "Reference" "PC2098"
			(at 0 0 180)
			(layer "F.SilkS")
			(hide yes)
			(effects
				(font
					(size 1.27 1.27)
				)
			)
		)
		(property "Value" ""
			(at 0 0 180)
			(layer "F.Fab")
			(effects
				(font
					(size 1.27 1.27)
				)
			)
		)
		(duplicate_pad_numbers_are_jumpers no)
		(fp_line
			(start 0.7874 0.4064)
			(end -0.7874 0.4064)
			(stroke
				(width 0.1524)
				(type default)
			)
			(layer "F.SilkS")
		)
		(fp_line
			(start 0.7874 -0.4064)
			(end 0.7874 0.4064)
			(stroke
				(width 0.1524)
				(type default)
			)
			(layer "F.SilkS")
		)
		(fp_line
			(start -0.7874 0.4064)
			(end -0.7874 -0.4064)
			(stroke
				(width 0.1524)
				(type default)
			)
			(layer "F.SilkS")
		)
		(fp_line
			(start -0.7874 -0.4064)
			(end 0.7874 -0.4064)
			(stroke
				(width 0.1524)
				(type default)
			)
			(layer "F.SilkS")
		)
		(fp_line
			(start 0.67945 0.3048)
			(end 0.120396 0.3048)
			(stroke
				(width 0.1)
				(type default)
			)
			(layer "F.Fab")
		)
		(fp_line
			(start 0.67945 -0.3048)
			(end 0.67945 0.3048)
			(stroke
				(width 0.1)
				(type default)
			)
			(layer "F.Fab")
		)
		(fp_line
			(start 0.12065 -0.2794)
			(end 0.12065 -0.3048)
			(stroke
				(width 0.1)
				(type default)
			)
			(layer "F.Fab")
		)
		(fp_line
			(start 0.12065 -0.3048)
			(end 0.67945 -0.3048)
			(stroke
				(width 0.1)
				(type default)
			)
			(layer "F.Fab")
		)
		(fp_line
			(start 0.120396 0.3048)
			(end 0.120396 0.2794)
			(stroke
				(width 0.1)
				(type default)
			)
			(layer "F.Fab")
		)
		(fp_line
			(start 0.120396 0.2794)
			(end -0.12065 0.2794)
			(stroke
				(width 0.1)
				(type default)
			)
			(layer "F.Fab")
		)
		(fp_line
			(start -0.12065 0.3048)
			(end -0.67945 0.3048)
			(stroke
				(width 0.1)
				(type default)
			)
			(layer "F.Fab")
		)
		(fp_line
			(start -0.12065 0.2794)
			(end -0.12065 0.3048)
			(stroke
				(width 0.1)
				(type default)
			)
			(layer "F.Fab")
		)
		(fp_line
			(start -0.12065 -0.2794)
			(end 0.12065 -0.2794)
			(stroke
				(width 0.1)
				(type default)
			)
			(layer "F.Fab")
		)
		(fp_line
			(start -0.12065 -0.305054)
			(end -0.12065 -0.2794)
			(stroke
				(width 0.1)
				(type default)
			)
			(layer "F.Fab")
		)
		(fp_line
			(start -0.67945 0.3048)
			(end -0.67945 -0.305054)
			(stroke
				(width 0.1)
				(type default)
			)
			(layer "F.Fab")
		)
		(fp_line
			(start -0.67945 -0.305054)
			(end -0.12065 -0.305054)
			(stroke
				(width 0.1)
				(type default)
			)
			(layer "F.Fab")
		)
		(pad "1" smd circle
			(at -0.40005 0 180)
			(size 0 0)
			(layers "F.Cu" "F.Mask" "F.Paste")
			(net "P12V_OCP_VCC_2")
		)
		(pad "2" smd circle
			(at 0.40005 0 180)
			(size 0 0)
			(layers "F.Cu" "F.Mask" "F.Paste")
			(net "GND")
		)
	)
)
